# ZAIUS-LV_CARD-EVT1-X00-BOM-X01_20160825.xls — TLA (bom)
| FOXCONN TECHNOLOGY GROUP |  |  |  |  |  |  |  |  |  |
| BILL OF MATERIAL |  |  |  |  |  |  |  |  |  |
| AA P/N | 1A42F9300-600-G | CUSTOMER |  | Customer P/N |  | Product Code |  |  |  |
| PWA P/N | 10035W000-600-G | PWA DESCRIPTION | ASSY,PCIe LV PASS THROUGH CARD |  |  | PWA REV | X00 | Prepared By SE |  |
| Item | FOXCONN P/N | Dell P/N | Part Description | Manufacturer  Full Name | Manufacturer  Part Number | Qty | RoHS Status | Location | Remark |
| 1 | 7J-004-938 |  | L6 LABEL ( 12.7*11.1mm) | FOXCONN / EPD1 | 7J-004-938 | 1 | G |  |  |
| 2 | TBD |  | Label for customer PN & SN, 1.25" (31.75mm) x 0.5"(6.35mm) | FOXCONN / EPD1 | TBD | 2 | G |  | For customer PN & SN label requirement. |
